(kicad_pcb
	(version 20260206)
	(generator "pcbnew")
	(generator_version "10.0")
	(general
		(thickness 1.6)
		(legacy_teardrops no)
	)
	(paper "A4")
	(title_block
		(title "Bryce Canyon_F.DPB_16315-1-OCP.brd")
		(comment 1 "Bryce Canyon / footprints 1030-1032 of 2223")
	)
	(layers
		(0 "F.Cu" signal "TOP")
		(4 "In1.Cu" signal "L2GND")
		(6 "In2.Cu" signal "L3")
		(8 "In3.Cu" signal "L4GND")
		(10 "In4.Cu" signal "L5")
		(12 "In5.Cu" signal "L6VCC")
		(14 "In6.Cu" signal "L7VCC")
		(16 "In7.Cu" signal "L8")
		(18 "In8.Cu" signal "L9GND")
		(20 "In9.Cu" signal "L10")
		(22 "In10.Cu" signal "L11GND")
		(2 "B.Cu" signal "BOTTOM")
		(9 "F.Adhes" user "F.Adhesive")
		(11 "B.Adhes" user "B.Adhesive")
		(13 "F.Paste" user "Package Geometry/Pastemask Top")
		(15 "B.Paste" user "Package Geometry/Pastemask Bottom")
		(5 "F.SilkS" user "Ref Des/Silkscreen Top")
		(7 "B.SilkS" user "Ref Des/Silkscreen Bottom")
		(1 "F.Mask" user "Board Geometry/Soldermask Top")
		(3 "B.Mask" user "Board Geometry/Soldermask Bottom")
		(17 "Dwgs.User" user "User.Drawings")
		(19 "Cmts.User" user "User.Comments")
		(21 "Eco1.User" user "User.Eco1")
		(23 "Eco2.User" user "User.Eco2")
		(25 "Edge.Cuts" user "Board Geometry/Outline")
		(27 "Margin" user)
		(31 "F.CrtYd" user "Package Geometry/Place Bound Top")
		(29 "B.CrtYd" user "Package Geometry/Place Bound Bottom")
		(35 "F.Fab" user "Ref Des/Assembly Top")
		(33 "B.Fab" user "Ref Des/Assembly Bottom")
	)
	(footprint ""
		(layer "F.Cu")
		(at 59.749944 -287.910016 -90)
		(property "Reference" "HDDSAS1"
			(at 0 0 270)
			(layer "F.SilkS")
			(hide yes)
			(effects
				(font
					(size 1.27 1.27)
				)
			)
		)
		(property "Value" "SKT-SAS15P-14P-45-GP"
			(at -20.7645 -8.9789 270)
			(unlocked yes)
			(layer "F.Fab")
			(hide yes)
			(effects
				(font
					(size 1.016 1.016)
					(thickness 0.1524)
				)
			)
		)
		(property "Device Type" "10120818-001C-TRLF"
			(at -20.7645 -10.5029 270)
			(unlocked yes)
			(layer "F.Fab")
			(hide yes)
			(effects
				(font
					(size 1.016 1.016)
					(thickness 0.1524)
				)
			)
		)
		(duplicate_pad_numbers_are_jumpers no)
		(fp_line
			(start 1.651 4.2926)
			(end 1.651 3.0099)
			(stroke
				(width 0.1524)
				(type default)
			)
			(layer "F.SilkS")
		)
		(fp_line
			(start 8.509 4.2926)
			(end 1.651 4.2926)
			(stroke
				(width 0.1524)
				(type default)
			)
			(layer "F.SilkS")
		)
		(fp_line
			(start -23.4188 3.0099)
			(end -23.4188 -3.2512)
			(stroke
				(width 0.1524)
				(type default)
			)
			(layer "F.SilkS")
		)
		(fp_line
			(start 1.651 3.0099)
			(end -23.4188 3.0099)
			(stroke
				(width 0.1524)
				(type default)
			)
			(layer "F.SilkS")
		)
		(fp_line
			(start 8.509 3.0099)
			(end 8.509 4.2926)
			(stroke
				(width 0.1524)
				(type default)
			)
			(layer "F.SilkS")
		)
		(fp_line
			(start 23.4188 3.0099)
			(end 8.509 3.0099)
			(stroke
				(width 0.1524)
				(type default)
			)
			(layer "F.SilkS")
		)
		(fp_line
			(start -23.4188 -3.2512)
			(end 23.4188 -3.2512)
			(stroke
				(width 0.1524)
				(type default)
			)
			(layer "F.SilkS")
		)
		(fp_line
			(start 23.4188 -3.2512)
			(end 23.4188 3.0099)
			(stroke
				(width 0.1524)
				(type default)
			)
			(layer "F.SilkS")
		)
		(fp_line
			(start 15.5067 -3.3401)
			(end 16.2687 -3.3401)
			(stroke
				(width 0.3302)
				(type default)
			)
			(layer "F.SilkS")
		)
		(fp_poly
			(pts
				(xy 15.868904 -3.230372) (xy 16.503904 -3.865372) (xy 15.233904 -3.865372)
			)
			(stroke
				(width 0)
				(type default)
			)
			(fill yes)
			(layer "F.SilkS")
		)
		(fp_poly
			(pts
				(xy -22.8727 -2.7559) (xy 22.8727 -2.7559) (xy 22.8727 2.7559) (xy 8.255 2.7559) (xy 8.255 3.5179)
				(xy 1.905 3.5179) (xy 1.905 2.7559) (xy -22.8727 2.7559)
			)
			(stroke
				(width 0)
				(type default)
			)
			(fill no)
			(layer "F.CrtYd")
		)
		(fp_poly
			(pts
				(xy 1.397 4.5466) (xy 1.397 3.2639) (xy -23.6728 3.2639) (xy -23.6728 -3.5052) (xy 23.6728 -3.5052)
				(xy 23.6728 -0.00635) (xy 22.8727 -0.00635) (xy 22.8727 -2.7559) (xy -22.8727 -2.7559) (xy -22.8727 2.7559)
				(xy 1.905 2.7559) (xy 1.905 3.5179) (xy 8.255 3.5179) (xy 8.255 2.7559) (xy 22.8727 2.7559) (xy 22.8727 0.00635)
				(xy 23.6728 0.00635) (xy 23.6728 3.2639) (xy 8.763 3.2639) (xy 8.763 4.5466)
			)
			(stroke
				(width 0)
				(type default)
			)
			(fill no)
			(layer "F.CrtYd")
		)
		(fp_poly
			(pts
				(xy 1.397 4.5466) (xy 1.397 3.2639) (xy -23.6728 3.2639) (xy -23.6728 -3.5052) (xy 23.6728 -3.5052)
				(xy 23.6728 3.2639) (xy 8.763 3.2639) (xy 8.763 4.5466)
			)
			(stroke
				(width 0)
				(type default)
			)
			(fill no)
			(layer "F.Fab")
		)
		(pad "" np_thru_hole circle
			(at -18.874994 0 270)
			(size 0.254 0.254)
			(drill 1.3462)
			(layers "*.Cu" "*.Mask")
			(clearance 0.9017)
			(thermal_gap 0.9017)
		)
		(pad "" np_thru_hole circle
			(at 18.874994 0 270)
			(size 0.254 0.254)
			(drill 0.9398)
			(layers "*.Cu" "*.Mask")
			(clearance 0.6985)
			(thermal_gap 0.6985)
		)
		(pad "G1" smd rect
			(at 21.874988 0 270)
			(size 2.5908 2.5908)
			(layers "F.Cu" "F.Mask" "F.Paste")
			(net "GND")
		)
		(pad "G2" smd rect
			(at -21.874988 0 270)
			(size 2.5908 2.5908)
			(layers "F.Cu" "F.Mask" "F.Paste")
			(net "GND")
		)
		(pad "P1" smd rect
			(at 1.905 -1.82499 270)
			(size 0.6096 2.3622)
			(layers "F.Cu" "F.Mask" "F.Paste")
			(net "Net_2121")
		)
		(pad "P2" smd rect
			(at 0.635 -1.82499 270)
			(size 0.6096 2.3622)
			(layers "F.Cu" "F.Mask" "F.Paste")
			(net "Net_2122")
		)
		(pad "P3" smd rect
			(at -0.635 -1.82499 270)
			(size 0.6096 2.3622)
			(layers "F.Cu" "F.Mask" "F.Paste")
			(net "Net_2123")
		)
		(pad "P4" smd rect
			(at -1.905 -1.82499 270)
			(size 0.6096 2.3622)
			(layers "F.Cu" "F.Mask" "F.Paste")
			(net "GND")
		)
		(pad "P5" smd rect
			(at -3.175 -1.82499 270)
			(size 0.6096 2.3622)
			(layers "F.Cu" "F.Mask" "F.Paste")
			(net "HDD_PRSNT_1")
		)
		(pad "P6" smd rect
			(at -4.445 -1.82499 270)
			(size 0.6096 2.3622)
			(layers "F.Cu" "F.Mask" "F.Paste")
			(net "GND")
		)
		(pad "P7" smd rect
			(at -5.715 -1.82499 270)
			(size 0.6096 2.3622)
			(layers "F.Cu" "F.Mask" "F.Paste")
			(net "5V_PRE_1")
		)
		(pad "P8" smd rect
			(at -6.985 -1.82499 270)
			(size 0.6096 2.3622)
			(layers "F.Cu" "F.Mask" "F.Paste")
			(net "P5V_HDD1")
		)
		(pad "P9" smd rect
			(at -8.255 -1.82499 270)
			(size 0.6096 2.3622)
			(layers "F.Cu" "F.Mask" "F.Paste")
			(net "P5V_HDD1")
		)
		(pad "P10" smd rect
			(at -9.525 -1.82499 270)
			(size 0.6096 2.3622)
			(layers "F.Cu" "F.Mask" "F.Paste")
			(net "GND")
		)
		(pad "P11" smd rect
			(at -10.795 -1.82499 270)
			(size 0.6096 2.3622)
			(layers "F.Cu" "F.Mask" "F.Paste")
			(net "ACT_HDD_1")
		)
		(pad "P12" smd rect
			(at -12.065 -1.82499 270)
			(size 0.6096 2.3622)
			(layers "F.Cu" "F.Mask" "F.Paste")
			(net "GND")
		)
		(pad "P13" smd rect
			(at -13.335 -1.82499 270)
			(size 0.6096 2.3622)
			(layers "F.Cu" "F.Mask" "F.Paste")
			(net "12V_PRE_1")
		)
		(pad "P14" smd rect
			(at -14.605 -1.82499 270)
			(size 0.6096 2.3622)
			(layers "F.Cu" "F.Mask" "F.Paste")
			(net "P12V_HDD1")
		)
		(pad "P15" smd rect
			(at -15.875 -1.82499 270)
			(size 0.6096 2.3622)
			(layers "F.Cu" "F.Mask" "F.Paste")
			(net "P12V_HDD1")
		)
		(pad "S1" smd rect
			(at 15.875 -1.82499 270)
			(size 0.6096 2.3622)
			(layers "F.Cu" "F.Mask" "F.Paste")
			(net "GND")
		)
		(pad "S2" smd rect
			(at 14.605 -1.82499 270)
			(size 0.6096 2.3622)
			(layers "F.Cu" "F.Mask" "F.Paste")
			(net "SAS_HDD_RX_P1")
		)
		(pad "S3" smd rect
			(at 13.335 -1.82499 270)
			(size 0.6096 2.3622)
			(layers "F.Cu" "F.Mask" "F.Paste")
			(net "SAS_HDD_RX_N1")
		)
		(pad "S4" smd rect
			(at 12.065 -1.82499 270)
			(size 0.6096 2.3622)
			(layers "F.Cu" "F.Mask" "F.Paste")
			(net "GND")
		)
		(pad "S5" smd rect
			(at 10.795 -1.82499 270)
			(size 0.6096 2.3622)
			(layers "F.Cu" "F.Mask" "F.Paste")
			(net "PHY_DRV_A_TO_SCC_A_1_DN")
		)
		(pad "S6" smd rect
			(at 9.525 -1.82499 270)
			(size 0.6096 2.3622)
			(layers "F.Cu" "F.Mask" "F.Paste")
			(net "PHY_DRV_A_TO_SCC_A_1_DP")
		)
		(pad "S7" smd rect
			(at 8.255 -1.82499 270)
			(size 0.6096 2.3622)
			(layers "F.Cu" "F.Mask" "F.Paste")
			(net "GND")
		)
		(pad "S8" smd rect
			(at 7.480046 2.845054 270)
			(size 0.508 2.3622)
			(layers "F.Cu" "F.Mask" "F.Paste")
			(net "GND")
		)
		(pad "S9" smd rect
			(at 6.679946 2.845054 270)
			(size 0.508 2.3622)
			(layers "F.Cu" "F.Mask" "F.Paste")
			(net "Net_456")
		)
		(pad "S10" smd rect
			(at 5.8801 2.845054 270)
			(size 0.508 2.3622)
			(layers "F.Cu" "F.Mask" "F.Paste")
			(net "Net_348")
		)
		(pad "S11" smd rect
			(at 5.08 2.845054 270)
			(size 0.508 2.3622)
			(layers "F.Cu" "F.Mask" "F.Paste")
			(net "GND")
		)
		(pad "S12" smd rect
			(at 4.2799 2.845054 270)
			(size 0.508 2.3622)
			(layers "F.Cu" "F.Mask" "F.Paste")
			(net "Net_384")
		)
		(pad "S13" smd rect
			(at 3.480054 2.845054 270)
			(size 0.508 2.3622)
			(layers "F.Cu" "F.Mask" "F.Paste")
			(net "Net_420")
		)
		(pad "S14" smd rect
			(at 2.679954 2.845054 270)
			(size 0.508 2.3622)
			(layers "F.Cu" "F.Mask" "F.Paste")
			(net "GND")
		)
		(zone
			(layer "F.Cu")
			(hatch none 0.5)
			(connect_pads
				(clearance 0)
			)
			(min_thickness 0.25)
			(keepout
				(tracks allowed)
				(vias not_allowed)
				(pads allowed)
				(copperpour not_allowed)
				(footprints allowed)
			)
			(placement
				(enabled no)
				(sheetname "")
			)
			(fill
				(thermal_gap 0.5)
				(thermal_bridge_width 0.5)
				(island_removal_mode 0)
			)
			(polygon
				(pts
					(xy 63.407544 -304.648616) (xy 56.333644 -304.648616) (xy 56.333644 -311.582816) (xy 57.438544 -311.582816)
					(xy 57.438544 -307.468016) (xy 62.061344 -307.468016) (xy 62.061344 -311.582816) (xy 63.407544 -311.582816)
				)
			)
		)
		(zone
			(layer "F.Cu")
			(hatch none 0.5)
			(connect_pads
				(clearance 0)
			)
			(min_thickness 0.25)
			(keepout
				(tracks not_allowed)
				(vias allowed)
				(pads allowed)
				(copperpour not_allowed)
				(footprints allowed)
			)
			(placement
				(enabled no)
				(sheetname "")
			)
			(fill
				(thermal_gap 0.5)
				(thermal_bridge_width 0.5)
				(island_removal_mode 0)
			)
			(polygon
				(pts
					(xy 63.407544 -304.648616) (xy 56.333644 -304.648616) (xy 56.333644 -311.582816) (xy 57.438544 -311.582816)
					(xy 57.438544 -307.468016) (xy 62.061344 -307.468016) (xy 62.061344 -311.582816) (xy 63.407544 -311.582816)
				)
			)
		)
		(zone
			(layer "F.Cu")
			(hatch none 0.5)
			(connect_pads
				(clearance 0)
			)
			(min_thickness 0.25)
			(keepout
				(tracks not_allowed)
				(vias allowed)
				(pads allowed)
				(copperpour not_allowed)
				(footprints allowed)
			)
			(placement
				(enabled no)
				(sheetname "")
			)
			(fill
				(thermal_gap 0.5)
				(thermal_bridge_width 0.5)
				(island_removal_mode 0)
			)
			(polygon
				(pts
					(xy 63.407544 -271.171416) (xy 56.333644 -271.171416) (xy 56.333644 -264.237216) (xy 57.438544 -264.237216)
					(xy 57.438544 -268.352016) (xy 62.061344 -268.352016) (xy 62.061344 -264.237216) (xy 63.407544 -264.237216)
				)
			)
		)
		(zone
			(layer "F.Cu")
			(hatch none 0.5)
			(connect_pads
				(clearance 0)
			)
			(min_thickness 0.25)
			(keepout
				(tracks allowed)
				(vias not_allowed)
				(pads allowed)
				(copperpour not_allowed)
				(footprints allowed)
			)
			(placement
				(enabled no)
				(sheetname "")
			)
			(fill
				(thermal_gap 0.5)
				(thermal_bridge_width 0.5)
				(island_removal_mode 0)
			)
			(polygon
				(pts
					(xy 63.407544 -271.171416) (xy 56.333644 -271.171416) (xy 56.333644 -264.237216) (xy 57.438544 -264.237216)
					(xy 57.438544 -268.352016) (xy 62.061344 -268.352016) (xy 62.061344 -264.237216) (xy 63.407544 -264.237216)
				)
			)
		)
		(zone
			(layers "F.Cu" "B.Cu" "In1.Cu" "In2.Cu" "In3.Cu" "In4.Cu" "In5.Cu" "In6.Cu"
				"In7.Cu" "In8.Cu" "In9.Cu" "In10.Cu"
			)
			(hatch none 0.5)
			(connect_pads
				(clearance 0)
			)
			(min_thickness 0.25)
			(keepout
				(tracks not_allowed)
				(vias allowed)
				(pads allowed)
				(copperpour not_allowed)
				(footprints allowed)
			)
			(placement
				(enabled no)
				(sheetname "")
			)
			(fill
				(thermal_gap 0.5)
				(thermal_bridge_width 0.5)
				(island_removal_mode 0)
			)
			(polygon
				(pts
					(arc
						(start 60.524644 -269.035022)
						(mid 58.975244 -269.035022)
						(end 60.524644 -269.035022)
					)
				)
			)
		)
		(zone
			(layers "F.Cu" "B.Cu" "In1.Cu" "In2.Cu" "In3.Cu" "In4.Cu" "In5.Cu" "In6.Cu"
				"In7.Cu" "In8.Cu" "In9.Cu" "In10.Cu"
			)
			(hatch none 0.5)
			(connect_pads
				(clearance 0)
			)
			(min_thickness 0.25)
			(keepout
				(tracks not_allowed)
				(vias allowed)
				(pads allowed)
				(copperpour not_allowed)
				(footprints allowed)
			)
			(placement
				(enabled no)
				(sheetname "")
			)
			(fill
				(thermal_gap 0.5)
				(thermal_bridge_width 0.5)
				(island_removal_mode 0)
			)
			(polygon
				(pts
					(arc
						(start 60.727844 -306.78501)
						(mid 58.772044 -306.78501)
						(end 60.727844 -306.78501)
					)
				)
			)
		)
	)
	(footprint ""
		(layer "F.Cu")
		(at 162.378898 -65.064894 90)
		(property "Reference" "R778"
			(at 0 0 90)
			(layer "F.SilkS")
			(hide yes)
			(effects
				(font
					(size 1.27 1.27)
				)
			)
		)
		(property "Value" "220R3F-1-GP"
			(at -0.0254 -2.5146 90)
			(unlocked yes)
			(layer "F.Fab")
			(hide yes)
			(effects
				(font
					(size 1.016 1.016)
					(thickness 0.1524)
				)
			)
		)
		(property "Device Type" "R603H22"
			(at -0.0254 -4.0386 90)
			(unlocked yes)
			(layer "F.Fab")
			(hide yes)
			(effects
				(font
					(size 1.016 1.016)
					(thickness 0.1524)
				)
			)
		)
		(duplicate_pad_numbers_are_jumpers no)
		(fp_line
			(start 0.2032 0)
			(end 0.4826 0)
			(stroke
				(width 0.2032)
				(type default)
			)
			(layer "F.SilkS")
		)
		(fp_line
			(start -0.4826 0)
			(end -0.2032 0)
			(stroke
				(width 0.2032)
				(type default)
			)
			(layer "F.SilkS")
		)
		(fp_rect
			(start -0.5842 1.3335)
			(end 0.5842 -1.3335)
			(stroke
				(width 0)
				(type default)
			)
			(fill no)
			(layer "F.CrtYd")
		)
		(fp_rect
			(start -0.5842 1.3335)
			(end 0.5842 -1.3335)
			(stroke
				(width 0)
				(type default)
			)
			(fill no)
			(layer "F.Fab")
		)
		(pad "1" smd custom
			(at 0 -0.762 90)
			(size 0.2159 0.2159)
			(layers "F.Cu" "F.Mask" "F.Paste")
			(net "HDD_PRSNT_28")
			(options
				(clearance outline)
				(anchor circle)
			)
			(primitives
				(gr_poly
					(pts
						(arc
							(start -0.3302 -0.4318)
							(mid -0.402042 -0.402042)
							(end -0.4318 -0.3302)
						)
						(arc
							(start -0.4318 0.3302)
							(mid -0.402042 0.402042)
							(end -0.3302 0.4318)
						)
						(arc
							(start 0.3302 0.4318)
							(mid 0.402042 0.402042)
							(end 0.4318 0.3302)
						)
						(arc
							(start 0.4318 -0.3302)
							(mid 0.402042 -0.402042)
							(end 0.3302 -0.4318)
						)
					)
					(width 0)
					(fill yes)
				)
			)
		)
		(pad "2" smd custom
			(at 0 0.762 90)
			(size 0.2159 0.2159)
			(layers "F.Cu" "F.Mask" "F.Paste")
			(net "DRIVE_A_28_INS")
			(options
				(clearance outline)
				(anchor circle)
			)
			(primitives
				(gr_poly
					(pts
						(arc
							(start -0.3302 -0.4318)
							(mid -0.402042 -0.402042)
							(end -0.4318 -0.3302)
						)
						(arc
							(start -0.4318 0.3302)
							(mid -0.402042 0.402042)
							(end -0.3302 0.4318)
						)
						(arc
							(start 0.3302 0.4318)
							(mid 0.402042 0.402042)
							(end 0.4318 0.3302)
						)
						(arc
							(start 0.4318 -0.3302)
							(mid 0.402042 -0.402042)
							(end 0.3302 -0.4318)
						)
					)
					(width 0)
					(fill yes)
				)
			)
		)
	)
	(footprint ""
		(layer "F.Cu")
		(at 332.6384 -272.585942 180)
		(property "Reference" "R276"
			(at 0 0 180)
			(layer "F.SilkS")
			(hide yes)
			(effects
				(font
					(size 1.27 1.27)
				)
			)
		)
		(property "Value" "1KR2F-3-GP"
			(at 0.064008 -3.993896 180)
			(unlocked yes)
			(layer "F.Fab")
			(hide yes)
			(effects
				(font
					(size 1.016 1.016)
					(thickness 0.1524)
				)
			)
		)
		(property "Device Type" "R402H16"
			(at 0.064008 -5.517896 180)
			(unlocked yes)
			(layer "F.Fab")
			(hide yes)
			(effects
				(font
					(size 1.016 1.016)
					(thickness 0.1524)
				)
			)
		)
		(duplicate_pad_numbers_are_jumpers no)
		(fp_line
			(start 0.508 -0.9398)
			(end -0.508 -0.9398)
			(stroke
				(width 0.1524)
				(type default)
			)
			(layer "F.SilkS")
		)
		(fp_line
			(start -0.508 -0.9398)
			(end -0.508 0.9398)
			(stroke
				(width 0.1524)
				(type default)
			)
			(layer "F.SilkS")
		)
		(fp_rect
			(start -0.508 0.9398)
			(end 0.508 -0.9398)
			(stroke
				(width 0)
				(type default)
			)
			(fill no)
			(layer "F.CrtYd")
		)
		(fp_rect
			(start -0.508 0.9398)
			(end 0.508 -0.9398)
			(stroke
				(width 0)
				(type default)
			)
			(fill no)
			(layer "F.Fab")
		)
		(pad "1" smd custom
			(at 0 -0.4445 180)
			(size 0.1397 0.1397)
			(layers "F.Cu" "F.Mask" "F.Paste")
			(net "P3V3_STBY_A")
			(options
				(clearance outline)
				(anchor circle)
			)
			(primitives
				(gr_poly
					(pts
						(arc
							(start -0.1778 -0.2794)
							(mid -0.249642 -0.249642)
							(end -0.2794 -0.1778)
						)
						(arc
							(start -0.2794 0.1778)
							(mid -0.249642 0.249642)
							(end -0.1778 0.2794)
						)
						(arc
							(start 0.1778 0.2794)
							(mid 0.249642 0.249642)
							(end 0.2794 0.1778)
						)
						(arc
							(start 0.2794 -0.1778)
							(mid 0.249642 -0.249642)
							(end 0.1778 -0.2794)
						)
					)
					(width 0)
					(fill yes)
				)
			)
		)
		(pad "2" smd custom
			(at 0 0.4445 180)
			(size 0.1397 0.1397)
			(layers "F.Cu" "F.Mask" "F.Paste")
			(net "SW_PWR_R_HDD6")
			(options
				(clearance outline)
				(anchor circle)
			)
			(primitives
				(gr_poly
					(pts
						(arc
							(start -0.1778 -0.2794)
							(mid -0.249642 -0.249642)
							(end -0.2794 -0.1778)
						)
						(arc
							(start -0.2794 0.1778)
							(mid -0.249642 0.249642)
							(end -0.1778 0.2794)
						)
						(arc
							(start 0.1778 0.2794)
							(mid 0.249642 0.249642)
							(end 0.2794 0.1778)
						)
						(arc
							(start 0.2794 -0.1778)
							(mid 0.249642 -0.249642)
							(end 0.1778 -0.2794)
						)
					)
					(width 0)
					(fill yes)
				)
			)
		)
	)
)
